(kicad_pcb
	(version 20260206)
	(generator "pcbnew")
	(generator_version "10.0")
	(general
		(thickness 1.6)
		(legacy_teardrops no)
	)
	(paper "A4")
	(title_block
		(title "peb — Lightning_PEB_BRD.brd")
		(comment 1 "Lightning (Wiwynn / Facebook NVMe JBOF) / footprints 1299-1306 of 2563")
	)
	(layers
		(0 "F.Cu" signal "TOP")
		(4 "In1.Cu" signal "L2GND")
		(6 "In2.Cu" signal "L3")
		(8 "In3.Cu" signal "L4VCC")
		(10 "In4.Cu" signal "L5VCC")
		(12 "In5.Cu" signal "L6")
		(14 "In6.Cu" signal "L7GND")
		(2 "B.Cu" signal "BOTTOM")
		(9 "F.Adhes" user "F.Adhesive")
		(11 "B.Adhes" user "B.Adhesive")
		(13 "F.Paste" user "Package Geometry/Pastemask Top")
		(15 "B.Paste" user "Package Geometry/Pastemask Bottom")
		(5 "F.SilkS" user "Ref Des/Silkscreen Top")
		(7 "B.SilkS" user "Ref Des/Silkscreen Bottom")
		(1 "F.Mask" user "Board Geometry/Soldermask Top")
		(3 "B.Mask" user "Board Geometry/Soldermask Bottom")
		(17 "Dwgs.User" user "User.Drawings")
		(19 "Cmts.User" user "User.Comments")
		(21 "Eco1.User" user "User.Eco1")
		(23 "Eco2.User" user "User.Eco2")
		(25 "Edge.Cuts" user "Board Geometry/Outline")
		(27 "Margin" user)
		(31 "F.CrtYd" user "Package Geometry/Place Bound Top")
		(29 "B.CrtYd" user "Package Geometry/Place Bound Bottom")
		(35 "F.Fab" user "Ref Des/Assembly Top")
		(33 "B.Fab" user "Ref Des/Assembly Bottom")
	)
	(footprint ""
		(layer "F.Cu")
		(at 302.49749 -33.540192)
		(property "Reference" "C24"
			(at 0 0 0)
			(layer "F.SilkS")
			(hide yes)
			(effects
				(font
					(size 1.27 1.27)
				)
			)
		)
		(property "Value" "SCD22U10V2KX-1GP"
			(at 1.1811 -2.7051 0)
			(unlocked yes)
			(layer "F.Fab")
			(hide yes)
			(effects
				(font
					(size 1.016 1.016)
					(thickness 0.1524)
				)
			)
		)
		(property "Device Type" "C402H22"
			(at 1.1811 -4.2291 0)
			(unlocked yes)
			(layer "F.Fab")
			(hide yes)
			(effects
				(font
					(size 1.016 1.016)
					(thickness 0.1524)
				)
			)
		)
		(duplicate_pad_numbers_are_jumpers no)
		(fp_rect
			(start -0.4318 0.9525)
			(end 0.4318 -0.9525)
			(stroke
				(width 0)
				(type default)
			)
			(fill no)
			(layer "F.CrtYd")
		)
		(fp_rect
			(start -0.4318 0.9525)
			(end 0.4318 -0.9525)
			(stroke
				(width 0)
				(type default)
			)
			(fill no)
			(layer "F.Fab")
		)
		(pad "1" smd custom
			(at 0 -0.4445)
			(size 0.1524 0.1524)
			(layers "F.Cu" "F.Mask" "F.Paste")
			(net "PCIE_TX_CAP_N6")
			(options
				(clearance outline)
				(anchor circle)
			)
			(primitives
				(gr_poly
					(pts
						(arc
							(start 0.3048 -0.2032)
							(mid 0.275042 -0.275042)
							(end 0.2032 -0.3048)
						)
						(arc
							(start -0.2032 -0.3048)
							(mid -0.275042 -0.275042)
							(end -0.3048 -0.2032)
						)
						(arc
							(start -0.3048 0.2032)
							(mid -0.275042 0.275042)
							(end -0.2032 0.3048)
						)
						(arc
							(start 0.2032 0.3048)
							(mid 0.275042 0.275042)
							(end 0.3048 0.2032)
						)
					)
					(width 0)
					(fill yes)
				)
			)
		)
		(pad "2" smd custom
			(at 0 0.4445)
			(size 0.1524 0.1524)
			(layers "F.Cu" "F.Mask" "F.Paste")
			(net "PCIE_TX_N6")
			(options
				(clearance outline)
				(anchor circle)
			)
			(primitives
				(gr_poly
					(pts
						(arc
							(start 0.3048 -0.2032)
							(mid 0.275042 -0.275042)
							(end 0.2032 -0.3048)
						)
						(arc
							(start -0.2032 -0.3048)
							(mid -0.275042 -0.275042)
							(end -0.3048 -0.2032)
						)
						(arc
							(start -0.3048 0.2032)
							(mid -0.275042 0.275042)
							(end -0.2032 0.3048)
						)
						(arc
							(start 0.2032 0.3048)
							(mid 0.275042 0.275042)
							(end 0.3048 0.2032)
						)
					)
					(width 0)
					(fill yes)
				)
			)
		)
	)
	(footprint ""
		(layer "F.Cu")
		(at 59.182 -42.926 -90)
		(property "Reference" "PC33"
			(at 0 0 270)
			(layer "F.SilkS")
			(hide yes)
			(effects
				(font
					(size 1.27 1.27)
				)
			)
		)
		(property "Value" "SC10U25V5KX-GP"
			(at -0.0762 -6.1214 270)
			(unlocked yes)
			(layer "F.Fab")
			(hide yes)
			(effects
				(font
					(size 1.016 1.016)
					(thickness 0.1524)
				)
			)
		)
		(property "Device Type" "C805H56"
			(at -0.0762 -8.1534 270)
			(unlocked yes)
			(layer "F.Fab")
			(hide yes)
			(effects
				(font
					(size 1.016 1.016)
					(thickness 0.1524)
				)
			)
		)
		(duplicate_pad_numbers_are_jumpers no)
		(fp_line
			(start 0.635 0)
			(end -0.635 0)
			(stroke
				(width 0.508)
				(type default)
			)
			(layer "F.SilkS")
		)
		(fp_rect
			(start -0.9652 1.778)
			(end 0.9652 -1.778)
			(stroke
				(width 0)
				(type default)
			)
			(fill no)
			(layer "F.CrtYd")
		)
		(fp_poly
			(pts
				(xy -0.9652 -1.778) (xy 0.9652 -1.778) (xy 0.9652 1.778) (xy -0.9652 1.778)
			)
			(stroke
				(width 0)
				(type default)
			)
			(fill no)
			(layer "F.Fab")
		)
		(pad "1" smd rect
			(at 0 -0.9652 270)
			(size 1.397 1.143)
			(layers "F.Cu" "F.Mask" "F.Paste")
			(net "P3V3_STBY_VIN")
		)
		(pad "2" smd rect
			(at 0 0.9652 270)
			(size 1.397 1.143)
			(layers "F.Cu" "F.Mask" "F.Paste")
			(net "GND")
		)
	)
	(footprint ""
		(layer "F.Cu")
		(at 39.878 -204.216 -90)
		(property "Reference" "C696"
			(at 0 0 270)
			(layer "F.SilkS")
			(hide yes)
			(effects
				(font
					(size 1.27 1.27)
				)
			)
		)
		(property "Value" "SC220P50V3JN-GP"
			(at 0 -2.8194 270)
			(unlocked yes)
			(layer "F.Fab")
			(hide yes)
			(effects
				(font
					(size 1.016 1.016)
					(thickness 0.1524)
				)
			)
		)
		(property "Device Type" "C603H36"
			(at 0 -4.3434 270)
			(unlocked yes)
			(layer "F.Fab")
			(hide yes)
			(effects
				(font
					(size 1.016 1.016)
					(thickness 0.1524)
				)
			)
		)
		(duplicate_pad_numbers_are_jumpers no)
		(fp_line
			(start 0.508 0)
			(end -0.508 0)
			(stroke
				(width 0.2032)
				(type default)
			)
			(layer "F.SilkS")
		)
		(fp_rect
			(start -0.5842 1.3335)
			(end 0.5842 -1.3335)
			(stroke
				(width 0)
				(type default)
			)
			(fill no)
			(layer "F.CrtYd")
		)
		(fp_rect
			(start -0.5842 1.3335)
			(end 0.5842 -1.3335)
			(stroke
				(width 0)
				(type default)
			)
			(fill no)
			(layer "F.Fab")
		)
		(pad "1" smd custom
			(at 0 -0.762 270)
			(size 0.2159 0.2159)
			(layers "F.Cu" "F.Mask" "F.Paste")
			(net "BUF_I2C6_C_FCB_SDA_R")
			(options
				(clearance outline)
				(anchor circle)
			)
			(primitives
				(gr_poly
					(pts
						(arc
							(start -0.3302 -0.4318)
							(mid -0.402042 -0.402042)
							(end -0.4318 -0.3302)
						)
						(arc
							(start -0.4318 0.3302)
							(mid -0.402042 0.402042)
							(end -0.3302 0.4318)
						)
						(arc
							(start 0.3302 0.4318)
							(mid 0.402042 0.402042)
							(end 0.4318 0.3302)
						)
						(arc
							(start 0.4318 -0.3302)
							(mid 0.402042 -0.402042)
							(end 0.3302 -0.4318)
						)
					)
					(width 0)
					(fill yes)
				)
			)
		)
		(pad "2" smd custom
			(at 0 0.762 270)
			(size 0.2159 0.2159)
			(layers "F.Cu" "F.Mask" "F.Paste")
			(net "GND")
			(options
				(clearance outline)
				(anchor circle)
			)
			(primitives
				(gr_poly
					(pts
						(arc
							(start -0.3302 -0.4318)
							(mid -0.402042 -0.402042)
							(end -0.4318 -0.3302)
						)
						(arc
							(start -0.4318 0.3302)
							(mid -0.402042 0.402042)
							(end -0.3302 0.4318)
						)
						(arc
							(start 0.3302 0.4318)
							(mid 0.402042 0.402042)
							(end 0.4318 0.3302)
						)
						(arc
							(start 0.4318 -0.3302)
							(mid 0.402042 -0.402042)
							(end 0.3302 -0.4318)
						)
					)
					(width 0)
					(fill yes)
				)
			)
		)
	)
	(footprint ""
		(layer "F.Cu")
		(at 20.6502 -192.5066 90)
		(property "Reference" "R2108"
			(at 0 0 90)
			(layer "F.SilkS")
			(hide yes)
			(effects
				(font
					(size 1.27 1.27)
				)
			)
		)
		(property "Value" "3K74R2F-GP"
			(at 0.064008 -3.993896 90)
			(unlocked yes)
			(layer "F.Fab")
			(hide yes)
			(effects
				(font
					(size 1.016 1.016)
					(thickness 0.1524)
				)
			)
		)
		(property "Device Type" "R402H16"
			(at 0.064008 -5.517896 90)
			(unlocked yes)
			(layer "F.Fab")
			(hide yes)
			(effects
				(font
					(size 1.016 1.016)
					(thickness 0.1524)
				)
			)
		)
		(duplicate_pad_numbers_are_jumpers no)
		(fp_line
			(start 0.508 -0.9398)
			(end -0.508 -0.9398)
			(stroke
				(width 0.1524)
				(type default)
			)
			(layer "F.SilkS")
		)
		(fp_line
			(start -0.508 -0.9398)
			(end -0.508 0.9398)
			(stroke
				(width 0.1524)
				(type default)
			)
			(layer "F.SilkS")
		)
		(fp_rect
			(start -0.508 0.9398)
			(end 0.508 -0.9398)
			(stroke
				(width 0)
				(type default)
			)
			(fill no)
			(layer "F.CrtYd")
		)
		(fp_rect
			(start -0.508 0.9398)
			(end 0.508 -0.9398)
			(stroke
				(width 0)
				(type default)
			)
			(fill no)
			(layer "F.Fab")
		)
		(pad "1" smd custom
			(at 0 -0.4445 90)
			(size 0.1397 0.1397)
			(layers "F.Cu" "F.Mask" "F.Paste")
			(net "MB0_CM_OV_R")
			(options
				(clearance outline)
				(anchor circle)
			)
			(primitives
				(gr_poly
					(pts
						(arc
							(start -0.1778 -0.2794)
							(mid -0.249642 -0.249642)
							(end -0.2794 -0.1778)
						)
						(arc
							(start -0.2794 0.1778)
							(mid -0.249642 0.249642)
							(end -0.1778 0.2794)
						)
						(arc
							(start 0.1778 0.2794)
							(mid 0.249642 0.249642)
							(end 0.2794 0.1778)
						)
						(arc
							(start 0.2794 -0.1778)
							(mid 0.249642 -0.249642)
							(end 0.1778 -0.2794)
						)
					)
					(width 0)
					(fill yes)
				)
			)
		)
		(pad "2" smd custom
			(at 0 0.4445 90)
			(size 0.1397 0.1397)
			(layers "F.Cu" "F.Mask" "F.Paste")
			(net "AGND_CURRENT_MON")
			(options
				(clearance outline)
				(anchor circle)
			)
			(primitives
				(gr_poly
					(pts
						(arc
							(start -0.1778 -0.2794)
							(mid -0.249642 -0.249642)
							(end -0.2794 -0.1778)
						)
						(arc
							(start -0.2794 0.1778)
							(mid -0.249642 0.249642)
							(end -0.1778 0.2794)
						)
						(arc
							(start 0.1778 0.2794)
							(mid 0.249642 0.249642)
							(end 0.2794 0.1778)
						)
						(arc
							(start 0.2794 -0.1778)
							(mid 0.249642 -0.249642)
							(end 0.1778 -0.2794)
						)
					)
					(width 0)
					(fill yes)
				)
			)
		)
	)
	(footprint ""
		(layer "F.Cu")
		(at 171.165774 -51.102768 180)
		(property "Reference" "Q35"
			(at 0 0 180)
			(layer "F.SilkS")
			(hide yes)
			(effects
				(font
					(size 1.27 1.27)
				)
			)
		)
		(property "Value" "2N7002K-1-GP"
			(at 0.127 -8.9662 180)
			(unlocked yes)
			(layer "F.Fab")
			(hide yes)
			(effects
				(font
					(size 1.016 1.016)
					(thickness 0.1524)
				)
			)
		)
		(property "Device Type" "SOT23DGS2D4H44"
			(at 0.127 -10.4902 180)
			(unlocked yes)
			(layer "F.Fab")
			(hide yes)
			(effects
				(font
					(size 1.016 1.016)
					(thickness 0.1524)
				)
			)
		)
		(duplicate_pad_numbers_are_jumpers no)
		(fp_line
			(start 1.651 1.778)
			(end 1.651 -1.778)
			(stroke
				(width 0.1524)
				(type default)
			)
			(layer "F.SilkS")
		)
		(fp_line
			(start 1.651 -1.778)
			(end -1.651 -1.778)
			(stroke
				(width 0.1524)
				(type default)
			)
			(layer "F.SilkS")
		)
		(fp_line
			(start -1.651 1.778)
			(end 1.651 1.778)
			(stroke
				(width 0.1524)
				(type default)
			)
			(layer "F.SilkS")
		)
		(fp_line
			(start -1.651 -1.778)
			(end -1.651 1.778)
			(stroke
				(width 0.1524)
				(type default)
			)
			(layer "F.SilkS")
		)
		(fp_poly
			(pts
				(xy -1.778 1.8796) (xy -1.778 -1.8796) (xy 1.778 -1.8796) (xy 1.778 1.8796)
			)
			(stroke
				(width 0)
				(type default)
			)
			(fill no)
			(layer "F.CrtYd")
		)
		(fp_poly
			(pts
				(xy -1.778 1.8796) (xy -1.778 -1.8796) (xy 1.778 -1.8796) (xy 1.778 1.8796)
			)
			(stroke
				(width 0)
				(type default)
			)
			(fill no)
			(layer "F.Fab")
		)
		(pad "D" smd custom
			(at 0 -0.9525 180)
			(size 0.1905 0.1905)
			(layers "F.Cu" "F.Mask" "F.Paste")
			(net "LED_Q_10")
			(options
				(clearance outline)
				(anchor circle)
			)
			(primitives
				(gr_poly
					(pts
						(arc
							(start -0.1778 0.5715)
							(mid -0.321484 0.511984)
							(end -0.381 0.3683)
						)
						(arc
							(start -0.381 -0.3683)
							(mid -0.321484 -0.511984)
							(end -0.1778 -0.5715)
						)
						(arc
							(start 0.1778 -0.5715)
							(mid 0.321484 -0.511984)
							(end 0.381 -0.3683)
						)
						(arc
							(start 0.381 0.3683)
							(mid 0.321484 0.511984)
							(end 0.1778 0.5715)
						)
					)
					(width 0)
					(fill yes)
				)
			)
		)
		(pad "G" smd custom
			(at -0.98425 0.9525 180)
			(size 0.1905 0.1905)
			(layers "F.Cu" "F.Mask" "F.Paste")
			(net "VS2_LED_R")
			(options
				(clearance outline)
				(anchor circle)
			)
			(primitives
				(gr_poly
					(pts
						(arc
							(start -0.1778 0.5715)
							(mid -0.321484 0.511984)
							(end -0.381 0.3683)
						)
						(arc
							(start -0.381 -0.3683)
							(mid -0.321484 -0.511984)
							(end -0.1778 -0.5715)
						)
						(arc
							(start 0.1778 -0.5715)
							(mid 0.321484 -0.511984)
							(end 0.381 -0.3683)
						)
						(arc
							(start 0.381 0.3683)
							(mid 0.321484 0.511984)
							(end 0.1778 0.5715)
						)
					)
					(width 0)
					(fill yes)
				)
			)
		)
		(pad "S" smd custom
			(at 0.98425 0.9525 180)
			(size 0.1905 0.1905)
			(layers "F.Cu" "F.Mask" "F.Paste")
			(net "GND")
			(options
				(clearance outline)
				(anchor circle)
			)
			(primitives
				(gr_poly
					(pts
						(arc
							(start -0.1778 0.5715)
							(mid -0.321484 0.511984)
							(end -0.381 0.3683)
						)
						(arc
							(start -0.381 -0.3683)
							(mid -0.321484 -0.511984)
							(end -0.1778 -0.5715)
						)
						(arc
							(start 0.1778 -0.5715)
							(mid 0.321484 -0.511984)
							(end 0.381 -0.3683)
						)
						(arc
							(start 0.381 0.3683)
							(mid 0.321484 0.511984)
							(end 0.1778 0.5715)
						)
					)
					(width 0)
					(fill yes)
				)
			)
		)
	)
	(footprint ""
		(layer "F.Cu")
		(at 318.444626 -33.42513)
		(property "Reference" "R413"
			(at 0 0 0)
			(layer "F.SilkS")
			(hide yes)
			(effects
				(font
					(size 1.27 1.27)
				)
			)
		)
		(property "Value" "0R2J-2-GP"
			(at 0.064008 -3.993896 0)
			(unlocked yes)
			(layer "F.Fab")
			(hide yes)
			(effects
				(font
					(size 1.016 1.016)
					(thickness 0.1524)
				)
			)
		)
		(property "Device Type" "R402H16"
			(at 0.064008 -5.517896 0)
			(unlocked yes)
			(layer "F.Fab")
			(hide yes)
			(effects
				(font
					(size 1.016 1.016)
					(thickness 0.1524)
				)
			)
		)
		(duplicate_pad_numbers_are_jumpers no)
		(fp_line
			(start -0.508 -0.9398)
			(end -0.508 0.9398)
			(stroke
				(width 0.1524)
				(type default)
			)
			(layer "F.SilkS")
		)
		(fp_line
			(start 0.508 -0.9398)
			(end -0.508 -0.9398)
			(stroke
				(width 0.1524)
				(type default)
			)
			(layer "F.SilkS")
		)
		(fp_rect
			(start -0.508 0.9398)
			(end 0.508 -0.9398)
			(stroke
				(width 0)
				(type default)
			)
			(fill no)
			(layer "F.CrtYd")
		)
		(fp_rect
			(start -0.508 0.9398)
			(end 0.508 -0.9398)
			(stroke
				(width 0)
				(type default)
			)
			(fill no)
			(layer "F.Fab")
		)
		(pad "1" smd custom
			(at 0 -0.4445)
			(size 0.1397 0.1397)
			(layers "F.Cu" "F.Mask" "F.Paste")
			(net "MINISAS_CN16_D_I2C_INT#")
			(options
				(clearance outline)
				(anchor circle)
			)
			(primitives
				(gr_poly
					(pts
						(arc
							(start -0.1778 -0.2794)
							(mid -0.249642 -0.249642)
							(end -0.2794 -0.1778)
						)
						(arc
							(start -0.2794 0.1778)
							(mid -0.249642 0.249642)
							(end -0.1778 0.2794)
						)
						(arc
							(start 0.1778 0.2794)
							(mid 0.249642 0.249642)
							(end 0.2794 0.1778)
						)
						(arc
							(start 0.2794 -0.1778)
							(mid 0.249642 -0.249642)
							(end 0.1778 -0.2794)
						)
					)
					(width 0)
					(fill yes)
				)
			)
		)
		(pad "2" smd custom
			(at 0 0.4445)
			(size 0.1397 0.1397)
			(layers "F.Cu" "F.Mask" "F.Paste")
			(net "CLK_N_8")
			(options
				(clearance outline)
				(anchor circle)
			)
			(primitives
				(gr_poly
					(pts
						(arc
							(start -0.1778 -0.2794)
							(mid -0.249642 -0.249642)
							(end -0.2794 -0.1778)
						)
						(arc
							(start -0.2794 0.1778)
							(mid -0.249642 0.249642)
							(end -0.1778 0.2794)
						)
						(arc
							(start 0.1778 0.2794)
							(mid 0.249642 0.249642)
							(end 0.2794 0.1778)
						)
						(arc
							(start 0.2794 -0.1778)
							(mid 0.249642 -0.249642)
							(end 0.1778 -0.2794)
						)
					)
					(width 0)
					(fill yes)
				)
			)
		)
	)
	(footprint ""
		(layer "F.Cu")
		(at 167.767 -93.2434 90)
		(property "Reference" "TP76"
			(at 0 0 90)
			(layer "F.SilkS")
			(hide yes)
			(effects
				(font
					(size 1.27 1.27)
				)
			)
		)
		(property "Value" "TPAD28-2-GP"
			(at -0.0127 -1.6637 90)
			(unlocked yes)
			(layer "F.Fab")
			(hide yes)
			(effects
				(font
					(size 1.016 1.016)
					(thickness 0.1524)
				)
			)
		)
		(property "Device Type" "TPAD28"
			(at -0.0127 -3.1877 90)
			(unlocked yes)
			(layer "F.Fab")
			(hide yes)
			(effects
				(font
					(size 1.016 1.016)
					(thickness 0.1524)
				)
			)
		)
		(duplicate_pad_numbers_are_jumpers no)
		(fp_poly
			(pts
				(arc
					(start 0 0.3556)
					(mid 0 -0.3556)
					(end 0 0.3556)
				)
			)
			(stroke
				(width 0)
				(type default)
			)
			(fill no)
			(layer "F.CrtYd")
		)
		(fp_poly
			(pts
				(arc
					(start 0 0.6096)
					(mid 0 -0.6096)
					(end 0 0.6096)
				)
			)
			(stroke
				(width 0)
				(type default)
			)
			(fill no)
			(layer "F.Fab")
		)
		(pad "1" smd circle
			(at 0 0 90)
			(size 0.7112 0.7112)
			(layers "F.Cu" "F.Mask" "F.Paste")
			(net "CLKGEN_N2")
		)
	)
	(footprint ""
		(layer "F.Cu")
		(at 240.538 -23.241 180)
		(property "Reference" "R783"
			(at 0 0 180)
			(layer "F.SilkS")
			(hide yes)
			(effects
				(font
					(size 1.27 1.27)
				)
			)
		)
		(property "Value" "4K7R2F-GP"
			(at 0.064008 -3.993896 180)
			(unlocked yes)
			(layer "F.Fab")
			(hide yes)
			(effects
				(font
					(size 1.016 1.016)
					(thickness 0.1524)
				)
			)
		)
		(property "Device Type" "R402H16"
			(at 0.064008 -5.517896 180)
			(unlocked yes)
			(layer "F.Fab")
			(hide yes)
			(effects
				(font
					(size 1.016 1.016)
					(thickness 0.1524)
				)
			)
		)
		(duplicate_pad_numbers_are_jumpers no)
		(fp_line
			(start 0.508 -0.9398)
			(end -0.508 -0.9398)
			(stroke
				(width 0.1524)
				(type default)
			)
			(layer "F.SilkS")
		)
		(fp_line
			(start -0.508 -0.9398)
			(end -0.508 0.9398)
			(stroke
				(width 0.1524)
				(type default)
			)
			(layer "F.SilkS")
		)
		(fp_rect
			(start -0.508 0.9398)
			(end 0.508 -0.9398)
			(stroke
				(width 0)
				(type default)
			)
			(fill no)
			(layer "F.CrtYd")
		)
		(fp_rect
			(start -0.508 0.9398)
			(end 0.508 -0.9398)
			(stroke
				(width 0)
				(type default)
			)
			(fill no)
			(layer "F.Fab")
		)
		(pad "1" smd custom
			(at 0 -0.4445 180)
			(size 0.1397 0.1397)
			(layers "F.Cu" "F.Mask" "F.Paste")
			(net "BOOTSTRAP3")
			(options
				(clearance outline)
				(anchor circle)
			)
			(primitives
				(gr_poly
					(pts
						(arc
							(start -0.1778 -0.2794)
							(mid -0.249642 -0.249642)
							(end -0.2794 -0.1778)
						)
						(arc
							(start -0.2794 0.1778)
							(mid -0.249642 0.249642)
							(end -0.1778 0.2794)
						)
						(arc
							(start 0.1778 0.2794)
							(mid 0.249642 0.249642)
							(end 0.2794 0.1778)
						)
						(arc
							(start 0.2794 -0.1778)
							(mid 0.249642 -0.249642)
							(end 0.1778 -0.2794)
						)
					)
					(width 0)
					(fill yes)
				)
			)
		)
		(pad "2" smd custom
			(at 0 0.4445 180)
			(size 0.1397 0.1397)
			(layers "F.Cu" "F.Mask" "F.Paste")
			(net "BOOTSTRAP_R_3")
			(options
				(clearance outline)
				(anchor circle)
			)
			(primitives
				(gr_poly
					(pts
						(arc
							(start -0.1778 -0.2794)
							(mid -0.249642 -0.249642)
							(end -0.2794 -0.1778)
						)
						(arc
							(start -0.2794 0.1778)
							(mid -0.249642 0.249642)
							(end -0.1778 0.2794)
						)
						(arc
							(start 0.1778 0.2794)
							(mid 0.249642 0.249642)
							(end 0.2794 0.1778)
						)
						(arc
							(start 0.2794 -0.1778)
							(mid 0.249642 -0.249642)
							(end 0.1778 -0.2794)
						)
					)
					(width 0)
					(fill yes)
				)
			)
		)
	)
)
